#ISCELL
  mstr_misc dns *
  *
#ISCELL
  pure_quanta quanta_title_block_c *
  *
#ISCELL
  standard offpage *
  page21_i1
#CELL
  pure_quanta q_res *
  page21_i100
#CELL
  pure_quanta q_res *
  page21_i101
#ISCELL
  standard offpage *
  page21_i108
#ISCELL
  standard offpage *
  page21_i109
#ISCELL
  standard offpage *
  page21_i110
#ISCELL
  standard offpage *
  page21_i111
#ISCELL
  logical_power universal_power *
  page21_i112
#ISCELL
  standard offpage *
  page21_i113
#ISCELL
  standard offpage *
  page21_i114
#ISCELL
  standard offpage *
  page21_i115
#ISCELL
  standard offpage *
  page21_i116
#ISCELL
  standard offpage *
  page21_i117
#ISCELL
  standard offpage *
  page21_i118
#ISCELL
  standard offpage *
  page21_i119
#ISCELL
  standard offpage *
  page21_i120
#ISCELL
  standard offpage *
  page21_i121
#ISCELL
  standard offpage *
  page21_i122
#ISCELL
  standard offpage *
  page21_i123
#ISCELL
  logical_power universal_gnd *
  page21_i124
#CELL
  pure_quanta q_res *
  page21_i125
#ISCELL
  standard offpage *
  page21_i126
#ISCELL
  standard offpage *
  page21_i127
#CELL
  pure_quanta q_res *
  page21_i128
#ISCELL
  standard offpage *
  page21_i133
#ISCELL
  standard offpage *
  page21_i134
#ISCELL
  standard offpage *
  page21_i135
#ISCELL
  standard offpage *
  page21_i136
#ISCELL
  standard offpage *
  page21_i138
#ISCELL
  logical_power universal_power *
  page21_i139
#ISCELL
  standard offpage *
  page21_i14
#ISCELL
  logical_power universal_gnd *
  page21_i145
#ISCELL
  logical_power universal_gnd *
  page21_i146
#CELL
  pure_quanta q_res *
  page21_i147
#ISCELL
  logical_power universal_power *
  page21_i148
#ISCELL
  standard offpage *
  page21_i149
#ISCELL
  standard offpage *
  page21_i152
#ISCELL
  standard offpage *
  page21_i154
#ISCELL
  standard offpage *
  page21_i155
#CELL
  pure_quanta q_res *
  page21_i156
#CELL
  pure_quanta q_res *
  page21_i157
#ISCELL
  logical_power universal_power *
  page21_i160
#CELL
  pure_quanta q_res *
  page21_i161
#ISCELL
  standard offpage *
  page21_i162
#CELL
  pure_quanta q_res *
  page21_i166
#CELL
  pure_quanta q_res *
  page21_i167
#CELL
  pure_quanta q_res *
  page21_i168
#ISCELL
  logical_power universal_power *
  page21_i169
#ISCELL
  logical_power universal_power *
  page21_i171
#CELL
  pure_quanta q_res *
  page21_i172
#CELL
  pure_quanta q_res *
  page21_i173
#CELL
  pure_quanta q_res *
  page21_i174
#CELL
  pure_quanta q_res *
  page21_i175
#CELL
  pure_quanta q_res *
  page21_i176
#CELL
  pure_quanta q_res *
  page21_i177
#CELL
  pure_quanta q_res *
  page21_i178
#CELL
  pure_quanta q_res *
  page21_i179
#CELL
  pure_quanta q_res *
  page21_i180
#CELL
  pure_quanta q_res *
  page21_i181
#CELL
  pure_quanta q_res *
  page21_i182
#ISCELL
  logical_power universal_gnd *
  page21_i20
#CELL
  pure_quanta q_cap *
  page21_i21
#ISCELL
  standard offpage *
  page21_i25
#ISCELL
  logical_power universal_power *
  page21_i3
#CELL
  pure_quanta q_res *
  page21_i33
#CELL
  pure_quanta q_res *
  page21_i35
#CELL
  pure_quanta q_res *
  page21_i42
#CELL
  pure_quanta q_res *
  page21_i43
#CELL
  pure_quanta q_res *
  page21_i45
#CELL
  pure_quanta q_res *
  page21_i46
#ISCELL
  logical_power universal_power *
  page21_i47
#CELL
  pure_quanta q_res *
  page21_i58
#CELL
  pure_quanta q_res *
  page21_i59
#CELL
  pure_quanta q_res *
  page21_i60
#CELL
  pure_quanta q_res *
  page21_i61
#CELL
  pure_quanta q_res *
  page21_i62
#CELL
  pure_quanta q_res *
  page21_i63
#CELL
  pure_quanta q_res *
  page21_i64
#CELL
  pure_quanta q_res *
  page21_i66
#CELL
  pure_quanta q_res *
  page21_i67
#ISCELL
  standard offpage *
  page21_i70
#ISCELL
  standard offpage *
  page21_i71
#ISCELL
  standard offpage *
  page21_i72
#ISCELL
  standard offpage *
  page21_i73
#ISCELL
  standard offpage *
  page21_i74
#ISCELL
  standard offpage *
  page21_i75
#ISCELL
  standard offpage *
  page21_i76
#ISCELL
  standard offpage *
  page21_i77
#ISCELL
  standard offpage *
  page21_i78
#CELL
  pure_quanta q_cap *
  page21_i80
#CELL
  pure_quanta q_cap *
  page21_i81
#CELL
  pure_quanta sconn67_nasa0s6730ts67 *
  page21_i84
#ISCELL
  standard offpage *
  page21_i85
#ISCELL
  standard offpage *
  page21_i86
#ISCELL
  standard offpage *
  page21_i87
#ISCELL
  standard offpage *
  page21_i89
#CELL
  pure_quanta q_res *
  page21_i98
#CELL
  pure_quanta q_res *
  page21_i99
